# T6G (Grand Teton) — schematic netlist excerpt (pin names and nets, part order shuffled) for the footprints in the layout excerpt that follows; sources: Cadence DE-HDL packaged netlist, KiCad conversion of 04192023_DAF0TMB3IC0_F0TG_MB_C_brd_V02_OCP.brd

C2525  Q_CAP  22UF 4V 20% X6S  pkg C0402  page 71 : A = PVDD18_S5_P0 ; B = GND

(kicad_pcb
	(version 20260206)
	(generator "pcbnew")
	(generator_version "10.0")
	(general
		(thickness 1.6)
		(legacy_teardrops no)
	)
	(paper "A4")
	(title_block
		(title "04192023_DAF0TMB3IC0_F0TG_MB_C_brd_V02_OCP.brd")
		(comment 1 "Grand Teton / footprints 3484-3484 of 8354")
	)
	(layers
		(0 "F.Cu" signal "TOP")
		(4 "In1.Cu" signal "GND")
		(6 "In2.Cu" signal "IN1")
		(8 "In3.Cu" signal "GND1")
		(10 "In4.Cu" signal "IN2")
		(12 "In5.Cu" signal "GND2")
		(14 "In6.Cu" signal "IN3")
		(16 "In7.Cu" signal "GND3")
		(18 "In8.Cu" signal "VCC")
		(20 "In9.Cu" signal "VCC1")
		(22 "In10.Cu" signal "GND4")
		(24 "In11.Cu" signal "IN4")
		(26 "In12.Cu" signal "GND5")
		(28 "In13.Cu" signal "IN5")
		(30 "In14.Cu" signal "GND6")
		(32 "In15.Cu" signal "IN6")
		(34 "In16.Cu" signal "GND7")
		(2 "B.Cu" signal "BOTTOM")
		(9 "F.Adhes" user "F.Adhesive")
		(11 "B.Adhes" user "B.Adhesive")
		(13 "F.Paste" user "Package Geometry/Pastemask Top")
		(15 "B.Paste" user "Package Geometry/Pastemask Bottom")
		(5 "F.SilkS" user "Ref Des/Silkscreen Top")
		(7 "B.SilkS" user "Ref Des/Silkscreen Bottom")
		(1 "F.Mask" user "Board Geometry/Soldermask Top")
		(3 "B.Mask" user "Board Geometry/Soldermask Bottom")
		(17 "Dwgs.User" user "User.Drawings")
		(19 "Cmts.User" user "User.Comments")
		(21 "Eco1.User" user "User.Eco1")
		(23 "Eco2.User" user "User.Eco2")
		(25 "Edge.Cuts" user "Board Geometry/Outline")
		(27 "Margin" user)
		(31 "F.CrtYd" user "Package Geometry/Place Bound Top")
		(29 "B.CrtYd" user "Package Geometry/Place Bound Bottom")
		(35 "F.Fab" user "Ref Des/Assembly Top")
		(33 "B.Fab" user "Ref Des/Assembly Bottom")
	)
	(footprint ""
		(layer "F.Cu")
		(at 356.29596 -257.744976)
		(property "Reference" "C2525"
			(at 0 0 0)
			(layer "F.SilkS")
			(hide yes)
			(effects
				(font
					(size 1.27 1.27)
				)
			)
		)
		(property "Value" ""
			(at 0 0 0)
			(layer "F.Fab")
			(effects
				(font
					(size 1.27 1.27)
				)
			)
		)
		(duplicate_pad_numbers_are_jumpers no)
		(fp_line
			(start -0.7874 -0.4064)
			(end 0.7874 -0.4064)
			(stroke
				(width 0.1524)
				(type default)
			)
			(layer "F.SilkS")
		)
		(fp_line
			(start -0.7874 0.4064)
			(end -0.7874 -0.4064)
			(stroke
				(width 0.1524)
				(type default)
			)
			(layer "F.SilkS")
		)
		(fp_line
			(start 0.7874 -0.4064)
			(end 0.7874 0.4064)
			(stroke
				(width 0.1524)
				(type default)
			)
			(layer "F.SilkS")
		)
		(fp_line
			(start 0.7874 0.4064)
			(end -0.7874 0.4064)
			(stroke
				(width 0.1524)
				(type default)
			)
			(layer "F.SilkS")
		)
		(fp_line
			(start -0.67945 -0.305054)
			(end -0.12065 -0.305054)
			(stroke
				(width 0.1)
				(type default)
			)
			(layer "F.Fab")
		)
		(fp_line
			(start -0.67945 0.3048)
			(end -0.67945 -0.305054)
			(stroke
				(width 0.1)
				(type default)
			)
			(layer "F.Fab")
		)
		(fp_line
			(start -0.12065 -0.305054)
			(end -0.12065 -0.2794)
			(stroke
				(width 0.1)
				(type default)
			)
			(layer "F.Fab")
		)
		(fp_line
			(start -0.12065 -0.2794)
			(end 0.12065 -0.2794)
			(stroke
				(width 0.1)
				(type default)
			)
			(layer "F.Fab")
		)
		(fp_line
			(start -0.12065 0.2794)
			(end -0.12065 0.3048)
			(stroke
				(width 0.1)
				(type default)
			)
			(layer "F.Fab")
		)
		(fp_line
			(start -0.12065 0.3048)
			(end -0.67945 0.3048)
			(stroke
				(width 0.1)
				(type default)
			)
			(layer "F.Fab")
		)
		(fp_line
			(start 0.120396 0.2794)
			(end -0.12065 0.2794)
			(stroke
				(width 0.1)
				(type default)
			)
			(layer "F.Fab")
		)
		(fp_line
			(start 0.120396 0.3048)
			(end 0.120396 0.2794)
			(stroke
				(width 0.1)
				(type default)
			)
			(layer "F.Fab")
		)
		(fp_line
			(start 0.12065 -0.3048)
			(end 0.67945 -0.3048)
			(stroke
				(width 0.1)
				(type default)
			)
			(layer "F.Fab")
		)
		(fp_line
			(start 0.12065 -0.2794)
			(end 0.12065 -0.3048)
			(stroke
				(width 0.1)
				(type default)
			)
			(layer "F.Fab")
		)
		(fp_line
			(start 0.67945 -0.3048)
			(end 0.67945 0.3048)
			(stroke
				(width 0.1)
				(type default)
			)
			(layer "F.Fab")
		)
		(fp_line
			(start 0.67945 0.3048)
			(end 0.120396 0.3048)
			(stroke
				(width 0.1)
				(type default)
			)
			(layer "F.Fab")
		)
		(pad "1" smd circle
			(at -0.40005 0)
			(size 0 0)
			(layers "F.Cu" "F.Mask" "F.Paste")
			(net "PVDD18_S5_P0")
		)
		(pad "2" smd circle
			(at 0.40005 0)
			(size 0 0)
			(layers "F.Cu" "F.Mask" "F.Paste")
			(net "GND")
		)
	)
)
